(kicad_pcb
	(version 20260206)
	(generator "pcbnew")
	(generator_version "10.0")
	(general
		(thickness 1.6)
		(legacy_teardrops no)
	)
	(paper "A4")
	(title_block
		(title "03242023_DA0F0TMBIJ0_F0T_Motherboard_J_brd_V01_OCP.brd")
		(comment 1 "Grand Teton / footprints 5891-5896 of 6105")
	)
	(layers
		(0 "F.Cu" signal "TOP")
		(4 "In1.Cu" signal "GND")
		(6 "In2.Cu" signal "IN1")
		(8 "In3.Cu" signal "GND1")
		(10 "In4.Cu" signal "IN2")
		(12 "In5.Cu" signal "GND2")
		(14 "In6.Cu" signal "IN3")
		(16 "In7.Cu" signal "GND3")
		(18 "In8.Cu" signal "VCC")
		(20 "In9.Cu" signal "VCC1")
		(22 "In10.Cu" signal "GND4")
		(24 "In11.Cu" signal "IN4")
		(26 "In12.Cu" signal "GND5")
		(28 "In13.Cu" signal "IN5")
		(30 "In14.Cu" signal "GND6")
		(32 "In15.Cu" signal "IN6")
		(34 "In16.Cu" signal "GND7")
		(2 "B.Cu" signal "BOTTOM")
		(9 "F.Adhes" user "F.Adhesive")
		(11 "B.Adhes" user "B.Adhesive")
		(13 "F.Paste" user "Package Geometry/Pastemask Top")
		(15 "B.Paste" user "Package Geometry/Pastemask Bottom")
		(5 "F.SilkS" user "Ref Des/Silkscreen Top")
		(7 "B.SilkS" user "Ref Des/Silkscreen Bottom")
		(1 "F.Mask" user "Board Geometry/Soldermask Top")
		(3 "B.Mask" user "Board Geometry/Soldermask Bottom")
		(17 "Dwgs.User" user "User.Drawings")
		(19 "Cmts.User" user "User.Comments")
		(21 "Eco1.User" user "User.Eco1")
		(23 "Eco2.User" user "User.Eco2")
		(25 "Edge.Cuts" user "Board Geometry/Outline")
		(27 "Margin" user)
		(31 "F.CrtYd" user "Package Geometry/Place Bound Top")
		(29 "B.CrtYd" user "Package Geometry/Place Bound Bottom")
		(35 "F.Fab" user "Ref Des/Assembly Top")
		(33 "B.Fab" user "Ref Des/Assembly Bottom")
	)
	(footprint ""
		(layer "B.Cu")
		(at 347.398594 -54.484016 90)
		(property "Reference" "C1255"
			(at 0 0 90)
			(layer "B.SilkS")
			(hide yes)
			(effects
				(font
					(size 1.27 1.27)
				)
				(justify mirror)
			)
		)
		(property "Value" ""
			(at 0 0 90)
			(layer "B.Fab")
			(effects
				(font
					(size 1.27 1.27)
				)
				(justify mirror)
			)
		)
		(duplicate_pad_numbers_are_jumpers no)
		(fp_line
			(start 1.2954 -0.5842)
			(end -1.2954 -0.5842)
			(stroke
				(width 0.1524)
				(type default)
			)
			(layer "B.SilkS")
		)
		(fp_line
			(start 0 -0.5842)
			(end 0 0.5842)
			(stroke
				(width 0.1524)
				(type default)
			)
			(layer "B.SilkS")
		)
		(fp_line
			(start -1.2954 -0.5842)
			(end -1.2954 0.5842)
			(stroke
				(width 0.1524)
				(type default)
			)
			(layer "B.SilkS")
		)
		(fp_line
			(start 1.2954 0.5842)
			(end 1.2954 -0.5842)
			(stroke
				(width 0.1524)
				(type default)
			)
			(layer "B.SilkS")
		)
		(fp_line
			(start -1.2954 0.5842)
			(end 1.2954 0.5842)
			(stroke
				(width 0.1524)
				(type default)
			)
			(layer "B.SilkS")
		)
		(fp_line
			(start 0.8636 -0.4572)
			(end -0.8636 -0.4572)
			(stroke
				(width 0.1)
				(type default)
			)
			(layer "B.Fab")
		)
		(fp_line
			(start -0.8636 -0.4572)
			(end -0.8636 -0.4064)
			(stroke
				(width 0.1)
				(type default)
			)
			(layer "B.Fab")
		)
		(fp_line
			(start 1.1938 -0.4064)
			(end 0.8636 -0.4064)
			(stroke
				(width 0.1)
				(type default)
			)
			(layer "B.Fab")
		)
		(fp_line
			(start 0.8636 -0.4064)
			(end 0.8636 -0.4572)
			(stroke
				(width 0.1)
				(type default)
			)
			(layer "B.Fab")
		)
		(fp_line
			(start -0.8636 -0.4064)
			(end -1.1938 -0.4064)
			(stroke
				(width 0.1)
				(type default)
			)
			(layer "B.Fab")
		)
		(fp_line
			(start -1.1938 -0.4064)
			(end -1.1938 0.4064)
			(stroke
				(width 0.1)
				(type default)
			)
			(layer "B.Fab")
		)
		(fp_line
			(start 1.1938 0.4064)
			(end 1.1938 -0.4064)
			(stroke
				(width 0.1)
				(type default)
			)
			(layer "B.Fab")
		)
		(fp_line
			(start 0.8636 0.4064)
			(end 1.1938 0.4064)
			(stroke
				(width 0.1)
				(type default)
			)
			(layer "B.Fab")
		)
		(fp_line
			(start -0.8636 0.4064)
			(end -0.8636 0.4572)
			(stroke
				(width 0.1)
				(type default)
			)
			(layer "B.Fab")
		)
		(fp_line
			(start -1.1938 0.4064)
			(end -0.8636 0.4064)
			(stroke
				(width 0.1)
				(type default)
			)
			(layer "B.Fab")
		)
		(fp_line
			(start 0.8636 0.4572)
			(end 0.8636 0.4064)
			(stroke
				(width 0.1)
				(type default)
			)
			(layer "B.Fab")
		)
		(fp_line
			(start -0.8636 0.4572)
			(end 0.8636 0.4572)
			(stroke
				(width 0.1)
				(type default)
			)
			(layer "B.Fab")
		)
		(pad "1" smd rect
			(at 0.7366 0)
			(size 0.7112 0.8128)
			(layers "B.Cu" "B.Mask" "B.Paste")
			(net "P1V8_PCH_PLL_AUX")
		)
		(pad "2" smd rect
			(at -0.7366 0)
			(size 0.7112 0.8128)
			(layers "B.Cu" "B.Mask" "B.Paste")
			(net "GND")
		)
	)
	(footprint ""
		(layer "B.Cu")
		(at 241.786156 -97.551748 -90)
		(property "Reference" "R442"
			(at 0 0 90)
			(layer "B.SilkS")
			(hide yes)
			(effects
				(font
					(size 1.27 1.27)
				)
				(justify mirror)
			)
		)
		(property "Value" ""
			(at 0 0 90)
			(layer "B.Fab")
			(effects
				(font
					(size 1.27 1.27)
				)
				(justify mirror)
			)
		)
		(duplicate_pad_numbers_are_jumpers no)
		(fp_line
			(start -1.2954 0.5842)
			(end 1.2954 0.5842)
			(stroke
				(width 0.1524)
				(type default)
			)
			(layer "B.SilkS")
		)
		(fp_line
			(start 1.2954 0.5842)
			(end 1.2954 -0.5842)
			(stroke
				(width 0.1524)
				(type default)
			)
			(layer "B.SilkS")
		)
		(fp_line
			(start -1.2954 -0.5842)
			(end -1.2954 0.5842)
			(stroke
				(width 0.1524)
				(type default)
			)
			(layer "B.SilkS")
		)
		(fp_line
			(start 1.2954 -0.5842)
			(end -1.2954 -0.5842)
			(stroke
				(width 0.1524)
				(type default)
			)
			(layer "B.SilkS")
		)
		(fp_line
			(start -0.8636 0.4572)
			(end 0.8636 0.4572)
			(stroke
				(width 0.1)
				(type default)
			)
			(layer "B.Fab")
		)
		(fp_line
			(start 0.8636 0.4572)
			(end 0.8636 0.4318)
			(stroke
				(width 0.1)
				(type default)
			)
			(layer "B.Fab")
		)
		(fp_line
			(start 0.8636 0.4318)
			(end 0.8636 0.4064)
			(stroke
				(width 0.1)
				(type default)
			)
			(layer "B.Fab")
		)
		(fp_line
			(start -1.1938 0.4064)
			(end -0.8636 0.4064)
			(stroke
				(width 0.1)
				(type default)
			)
			(layer "B.Fab")
		)
		(fp_line
			(start -0.8636 0.4064)
			(end -0.8636 0.4572)
			(stroke
				(width 0.1)
				(type default)
			)
			(layer "B.Fab")
		)
		(fp_line
			(start 0.8636 0.4064)
			(end 1.1938 0.4064)
			(stroke
				(width 0.1)
				(type default)
			)
			(layer "B.Fab")
		)
		(fp_line
			(start 1.1938 0.4064)
			(end 1.1938 -0.406654)
			(stroke
				(width 0.1)
				(type default)
			)
			(layer "B.Fab")
		)
		(fp_line
			(start -1.1938 -0.406654)
			(end -1.1938 0.4064)
			(stroke
				(width 0.1)
				(type default)
			)
			(layer "B.Fab")
		)
		(fp_line
			(start -0.8636 -0.406654)
			(end -1.1938 -0.406654)
			(stroke
				(width 0.1)
				(type default)
			)
			(layer "B.Fab")
		)
		(fp_line
			(start 0.8636 -0.406654)
			(end 0.8636 -0.4572)
			(stroke
				(width 0.1)
				(type default)
			)
			(layer "B.Fab")
		)
		(fp_line
			(start 1.1938 -0.406654)
			(end 0.8636 -0.406654)
			(stroke
				(width 0.1)
				(type default)
			)
			(layer "B.Fab")
		)
		(fp_line
			(start -0.8636 -0.4572)
			(end -0.8636 -0.406654)
			(stroke
				(width 0.1)
				(type default)
			)
			(layer "B.Fab")
		)
		(fp_line
			(start 0.8636 -0.4572)
			(end -0.8636 -0.4572)
			(stroke
				(width 0.1)
				(type default)
			)
			(layer "B.Fab")
		)
		(pad "1" smd rect
			(at 0.7366 0 180)
			(size 0.7112 0.8128)
			(layers "B.Cu" "B.Mask" "B.Paste")
			(net "P3V3_AUX_CLK_GEN_VDDXTAL_CK440")
		)
		(pad "2" smd rect
			(at -0.7366 0 180)
			(size 0.7112 0.8128)
			(layers "B.Cu" "B.Mask" "B.Paste")
			(net "P3V3_AUX_CLK_GEN_VDDA25M_CK440")
		)
	)
	(footprint ""
		(layer "B.Cu")
		(at 77.368908 -185.926476 -90)
		(property "Reference" "R90"
			(at 0 0 90)
			(layer "B.SilkS")
			(hide yes)
			(effects
				(font
					(size 1.27 1.27)
				)
				(justify mirror)
			)
		)
		(property "Value" ""
			(at 0 0 90)
			(layer "B.Fab")
			(effects
				(font
					(size 1.27 1.27)
				)
				(justify mirror)
			)
		)
		(duplicate_pad_numbers_are_jumpers no)
		(fp_line
			(start -0.7874 0.4064)
			(end 0.7874 0.4064)
			(stroke
				(width 0.1524)
				(type default)
			)
			(layer "B.SilkS")
		)
		(fp_line
			(start 0.7874 0.4064)
			(end 0.7874 -0.4064)
			(stroke
				(width 0.1524)
				(type default)
			)
			(layer "B.SilkS")
		)
		(fp_line
			(start -0.7874 -0.4064)
			(end -0.7874 0.4064)
			(stroke
				(width 0.1524)
				(type default)
			)
			(layer "B.SilkS")
		)
		(fp_line
			(start 0.7874 -0.4064)
			(end -0.7874 -0.4064)
			(stroke
				(width 0.1524)
				(type default)
			)
			(layer "B.SilkS")
		)
		(fp_line
			(start -0.67945 0.3048)
			(end -0.120396 0.3048)
			(stroke
				(width 0.1)
				(type default)
			)
			(layer "B.Fab")
		)
		(fp_line
			(start -0.120396 0.3048)
			(end -0.120396 0.2794)
			(stroke
				(width 0.1)
				(type default)
			)
			(layer "B.Fab")
		)
		(fp_line
			(start 0.12065 0.3048)
			(end 0.67945 0.3048)
			(stroke
				(width 0.1)
				(type default)
			)
			(layer "B.Fab")
		)
		(fp_line
			(start 0.67945 0.3048)
			(end 0.67945 -0.305054)
			(stroke
				(width 0.1)
				(type default)
			)
			(layer "B.Fab")
		)
		(fp_line
			(start -0.120396 0.2794)
			(end 0.12065 0.2794)
			(stroke
				(width 0.1)
				(type default)
			)
			(layer "B.Fab")
		)
		(fp_line
			(start 0.12065 0.2794)
			(end 0.12065 0.3048)
			(stroke
				(width 0.1)
				(type default)
			)
			(layer "B.Fab")
		)
		(fp_line
			(start -0.12065 -0.2794)
			(end -0.12065 -0.3048)
			(stroke
				(width 0.1)
				(type default)
			)
			(layer "B.Fab")
		)
		(fp_line
			(start 0.12065 -0.2794)
			(end -0.12065 -0.2794)
			(stroke
				(width 0.1)
				(type default)
			)
			(layer "B.Fab")
		)
		(fp_line
			(start -0.67945 -0.3048)
			(end -0.67945 0.3048)
			(stroke
				(width 0.1)
				(type default)
			)
			(layer "B.Fab")
		)
		(fp_line
			(start -0.12065 -0.3048)
			(end -0.67945 -0.3048)
			(stroke
				(width 0.1)
				(type default)
			)
			(layer "B.Fab")
		)
		(fp_line
			(start 0.12065 -0.305054)
			(end 0.12065 -0.2794)
			(stroke
				(width 0.1)
				(type default)
			)
			(layer "B.Fab")
		)
		(fp_line
			(start 0.67945 -0.305054)
			(end 0.12065 -0.305054)
			(stroke
				(width 0.1)
				(type default)
			)
			(layer "B.Fab")
		)
		(pad "1" smd circle
			(at 0.40005 0 90)
			(size 0 0)
			(layers "B.Cu" "B.Mask" "B.Paste")
			(net "PVNN_TERM_CPU1")
		)
		(pad "2" smd circle
			(at -0.40005 0 90)
			(size 0 0)
			(layers "B.Cu" "B.Mask" "B.Paste")
			(net "PU_CPU1_UPI0_AC_COUPLING")
		)
	)
	(footprint ""
		(layer "B.Cu")
		(at 341.00135 -37.574728 -90)
		(property "Reference" "R1554"
			(at 0 0 90)
			(layer "B.SilkS")
			(hide yes)
			(effects
				(font
					(size 1.27 1.27)
				)
				(justify mirror)
			)
		)
		(property "Value" ""
			(at 0 0 90)
			(layer "B.Fab")
			(effects
				(font
					(size 1.27 1.27)
				)
				(justify mirror)
			)
		)
		(duplicate_pad_numbers_are_jumpers no)
		(fp_line
			(start -0.7874 0.4064)
			(end 0.7874 0.4064)
			(stroke
				(width 0.1524)
				(type default)
			)
			(layer "B.SilkS")
		)
		(fp_line
			(start 0.7874 0.4064)
			(end 0.7874 -0.4064)
			(stroke
				(width 0.1524)
				(type default)
			)
			(layer "B.SilkS")
		)
		(fp_line
			(start -0.7874 -0.4064)
			(end -0.7874 0.4064)
			(stroke
				(width 0.1524)
				(type default)
			)
			(layer "B.SilkS")
		)
		(fp_line
			(start 0.7874 -0.4064)
			(end -0.7874 -0.4064)
			(stroke
				(width 0.1524)
				(type default)
			)
			(layer "B.SilkS")
		)
		(fp_line
			(start -0.67945 0.3048)
			(end -0.120396 0.3048)
			(stroke
				(width 0.1)
				(type default)
			)
			(layer "B.Fab")
		)
		(fp_line
			(start -0.120396 0.3048)
			(end -0.120396 0.2794)
			(stroke
				(width 0.1)
				(type default)
			)
			(layer "B.Fab")
		)
		(fp_line
			(start 0.12065 0.3048)
			(end 0.67945 0.3048)
			(stroke
				(width 0.1)
				(type default)
			)
			(layer "B.Fab")
		)
		(fp_line
			(start 0.67945 0.3048)
			(end 0.67945 -0.305054)
			(stroke
				(width 0.1)
				(type default)
			)
			(layer "B.Fab")
		)
		(fp_line
			(start -0.120396 0.2794)
			(end 0.12065 0.2794)
			(stroke
				(width 0.1)
				(type default)
			)
			(layer "B.Fab")
		)
		(fp_line
			(start 0.12065 0.2794)
			(end 0.12065 0.3048)
			(stroke
				(width 0.1)
				(type default)
			)
			(layer "B.Fab")
		)
		(fp_line
			(start -0.12065 -0.2794)
			(end -0.12065 -0.3048)
			(stroke
				(width 0.1)
				(type default)
			)
			(layer "B.Fab")
		)
		(fp_line
			(start 0.12065 -0.2794)
			(end -0.12065 -0.2794)
			(stroke
				(width 0.1)
				(type default)
			)
			(layer "B.Fab")
		)
		(fp_line
			(start -0.67945 -0.3048)
			(end -0.67945 0.3048)
			(stroke
				(width 0.1)
				(type default)
			)
			(layer "B.Fab")
		)
		(fp_line
			(start -0.12065 -0.3048)
			(end -0.67945 -0.3048)
			(stroke
				(width 0.1)
				(type default)
			)
			(layer "B.Fab")
		)
		(fp_line
			(start 0.12065 -0.305054)
			(end 0.12065 -0.2794)
			(stroke
				(width 0.1)
				(type default)
			)
			(layer "B.Fab")
		)
		(fp_line
			(start 0.67945 -0.305054)
			(end 0.12065 -0.305054)
			(stroke
				(width 0.1)
				(type default)
			)
			(layer "B.Fab")
		)
		(pad "1" smd circle
			(at 0.40005 0 90)
			(size 0 0)
			(layers "B.Cu" "B.Mask" "B.Paste")
			(net "P3V3_AUX")
		)
		(pad "2" smd circle
			(at -0.40005 0 90)
			(size 0 0)
			(layers "B.Cu" "B.Mask" "B.Paste")
			(net "FM_ME_AUTHN_FAIL")
		)
	)
	(footprint ""
		(layer "B.Cu")
		(at 27.304746 -319.268856 180)
		(property "Reference" "R897"
			(at 0 0 0)
			(layer "B.SilkS")
			(hide yes)
			(effects
				(font
					(size 1.27 1.27)
				)
				(justify mirror)
			)
		)
		(property "Value" ""
			(at 0 0 0)
			(layer "B.Fab")
			(effects
				(font
					(size 1.27 1.27)
				)
				(justify mirror)
			)
		)
		(duplicate_pad_numbers_are_jumpers no)
		(fp_line
			(start 0.7874 0.4064)
			(end 0.7874 -0.4064)
			(stroke
				(width 0.1524)
				(type default)
			)
			(layer "B.SilkS")
		)
		(fp_line
			(start 0.7874 -0.4064)
			(end -0.7874 -0.4064)
			(stroke
				(width 0.1524)
				(type default)
			)
			(layer "B.SilkS")
		)
		(fp_line
			(start -0.7874 0.4064)
			(end 0.7874 0.4064)
			(stroke
				(width 0.1524)
				(type default)
			)
			(layer "B.SilkS")
		)
		(fp_line
			(start -0.7874 -0.4064)
			(end -0.7874 0.4064)
			(stroke
				(width 0.1524)
				(type default)
			)
			(layer "B.SilkS")
		)
		(fp_line
			(start 0.67945 0.3048)
			(end 0.67945 -0.305054)
			(stroke
				(width 0.1)
				(type default)
			)
			(layer "B.Fab")
		)
		(fp_line
			(start 0.67945 -0.305054)
			(end 0.12065 -0.305054)
			(stroke
				(width 0.1)
				(type default)
			)
			(layer "B.Fab")
		)
		(fp_line
			(start 0.12065 0.3048)
			(end 0.67945 0.3048)
			(stroke
				(width 0.1)
				(type default)
			)
			(layer "B.Fab")
		)
		(fp_line
			(start 0.12065 0.2794)
			(end 0.12065 0.3048)
			(stroke
				(width 0.1)
				(type default)
			)
			(layer "B.Fab")
		)
		(fp_line
			(start 0.12065 -0.2794)
			(end -0.12065 -0.2794)
			(stroke
				(width 0.1)
				(type default)
			)
			(layer "B.Fab")
		)
		(fp_line
			(start 0.12065 -0.305054)
			(end 0.12065 -0.2794)
			(stroke
				(width 0.1)
				(type default)
			)
			(layer "B.Fab")
		)
		(fp_line
			(start -0.120396 0.3048)
			(end -0.120396 0.2794)
			(stroke
				(width 0.1)
				(type default)
			)
			(layer "B.Fab")
		)
		(fp_line
			(start -0.120396 0.2794)
			(end 0.12065 0.2794)
			(stroke
				(width 0.1)
				(type default)
			)
			(layer "B.Fab")
		)
		(fp_line
			(start -0.12065 -0.2794)
			(end -0.12065 -0.3048)
			(stroke
				(width 0.1)
				(type default)
			)
			(layer "B.Fab")
		)
		(fp_line
			(start -0.12065 -0.3048)
			(end -0.67945 -0.3048)
			(stroke
				(width 0.1)
				(type default)
			)
			(layer "B.Fab")
		)
		(fp_line
			(start -0.67945 0.3048)
			(end -0.120396 0.3048)
			(stroke
				(width 0.1)
				(type default)
			)
			(layer "B.Fab")
		)
		(fp_line
			(start -0.67945 -0.3048)
			(end -0.67945 0.3048)
			(stroke
				(width 0.1)
				(type default)
			)
			(layer "B.Fab")
		)
		(pad "1" smd circle
			(at 0.40005 0)
			(size 0 0)
			(layers "B.Cu" "B.Mask" "B.Paste")
			(net "PWRGD_CHC_CPU1_DIMM1")
		)
		(pad "2" smd circle
			(at -0.40005 0)
			(size 0 0)
			(layers "B.Cu" "B.Mask" "B.Paste")
			(net "PWRGD_FAIL_CPU1_CD")
		)
	)
	(footprint ""
		(layer "B.Cu")
		(at 126.67742 -31.526988 90)
		(property "Reference" "R4289"
			(at 0 0 90)
			(layer "B.SilkS")
			(hide yes)
			(effects
				(font
					(size 1.27 1.27)
				)
				(justify mirror)
			)
		)
		(property "Value" ""
			(at 0 0 90)
			(layer "B.Fab")
			(effects
				(font
					(size 1.27 1.27)
				)
				(justify mirror)
			)
		)
		(duplicate_pad_numbers_are_jumpers no)
		(fp_line
			(start 0.7874 -0.4064)
			(end -0.7874 -0.4064)
			(stroke
				(width 0.1524)
				(type default)
			)
			(layer "B.SilkS")
		)
		(fp_line
			(start -0.7874 -0.4064)
			(end -0.7874 0.4064)
			(stroke
				(width 0.1524)
				(type default)
			)
			(layer "B.SilkS")
		)
		(fp_line
			(start 0.7874 0.4064)
			(end 0.7874 -0.4064)
			(stroke
				(width 0.1524)
				(type default)
			)
			(layer "B.SilkS")
		)
		(fp_line
			(start -0.7874 0.4064)
			(end 0.7874 0.4064)
			(stroke
				(width 0.1524)
				(type default)
			)
			(layer "B.SilkS")
		)
		(fp_line
			(start 0.67945 -0.305054)
			(end 0.12065 -0.305054)
			(stroke
				(width 0.1)
				(type default)
			)
			(layer "B.Fab")
		)
		(fp_line
			(start 0.12065 -0.305054)
			(end 0.12065 -0.2794)
			(stroke
				(width 0.1)
				(type default)
			)
			(layer "B.Fab")
		)
		(fp_line
			(start -0.12065 -0.3048)
			(end -0.67945 -0.3048)
			(stroke
				(width 0.1)
				(type default)
			)
			(layer "B.Fab")
		)
		(fp_line
			(start -0.67945 -0.3048)
			(end -0.67945 0.3048)
			(stroke
				(width 0.1)
				(type default)
			)
			(layer "B.Fab")
		)
		(fp_line
			(start 0.12065 -0.2794)
			(end -0.12065 -0.2794)
			(stroke
				(width 0.1)
				(type default)
			)
			(layer "B.Fab")
		)
		(fp_line
			(start -0.12065 -0.2794)
			(end -0.12065 -0.3048)
			(stroke
				(width 0.1)
				(type default)
			)
			(layer "B.Fab")
		)
		(fp_line
			(start 0.12065 0.2794)
			(end 0.12065 0.3048)
			(stroke
				(width 0.1)
				(type default)
			)
			(layer "B.Fab")
		)
		(fp_line
			(start -0.120396 0.2794)
			(end 0.12065 0.2794)
			(stroke
				(width 0.1)
				(type default)
			)
			(layer "B.Fab")
		)
		(fp_line
			(start 0.67945 0.3048)
			(end 0.67945 -0.305054)
			(stroke
				(width 0.1)
				(type default)
			)
			(layer "B.Fab")
		)
		(fp_line
			(start 0.12065 0.3048)
			(end 0.67945 0.3048)
			(stroke
				(width 0.1)
				(type default)
			)
			(layer "B.Fab")
		)
		(fp_line
			(start -0.120396 0.3048)
			(end -0.120396 0.2794)
			(stroke
				(width 0.1)
				(type default)
			)
			(layer "B.Fab")
		)
		(fp_line
			(start -0.67945 0.3048)
			(end -0.120396 0.3048)
			(stroke
				(width 0.1)
				(type default)
			)
			(layer "B.Fab")
		)
		(pad "1" smd circle
			(at 0.40005 0 270)
			(size 0 0)
			(layers "B.Cu" "B.Mask" "B.Paste")
			(net "P3V3_AUX")
		)
		(pad "2" smd circle
			(at -0.40005 0 270)
			(size 0 0)
			(layers "B.Cu" "B.Mask" "B.Paste")
			(net "FM_USB3_1_RXDET_EN")
		)
	)
)
